# S9S_MB_2U (Grand Teton) — schematic netlist excerpt (pin names and nets, part order shuffled) for the footprints in the layout excerpt that follows; sources: Cadence DE-HDL packaged netlist, KiCad conversion of 03242023_DA0F0TMBIJ0_F0T_Motherboard_J_brd_V01_OCP.brd

J24  SCONN288_ADR50017P087CC  SCONN288_ADR50017-P087CC IO  pkg DDR288S_1-1VXB  page 105
  VIN_BULK0  = P12V_S3_AUX_CPU1_NVDIMM
  RFU0  = TP_CHD_CPU1_DIMM2_FRU_0
  VIN_MGMT  = P3V3_AUX
  HSCL  = I3C_SPD_DDRABCD_CPU1_LVC1_SCL_7
  HSDA  = I3C_SPD_DDRABCD_CPU1_LVC1_SDA
  VSS0  = GND
  DQ0_A  = M_D_CPU1_SA_DQ<0>
  VSS1  = GND
  DQ1_A  = M_D_CPU1_SA_DQ<1>
  VSS2  = GND
  DQS0_A_T  = M_D_CPU1_SA_DQS_DP<0>
  DQS0_A_C  = M_D_CPU1_SA_DQS_DN<0>
  VSS3  = GND
  DQ4_A  = M_D_CPU1_SA_DQ<4>
  VSS4  = GND
  DQ5_A  = M_D_CPU1_SA_DQ<5>
  VSS5  = GND
  DQ8_A  = M_D_CPU1_SA_DQ<8>
  VSS6  = GND
  DQ9_A  = M_D_CPU1_SA_DQ<9>
  VSS7  = GND
  DQS1_A_T  = M_D_CPU1_SA_DQS_DP<1>
  DQS1_A_C  = M_D_CPU1_SA_DQS_DN<1>
  VSS8  = GND
  DQ12_A  = M_D_CPU1_SA_DQ<12>
  VSS9  = GND
  DQ13_A  = M_D_CPU1_SA_DQ<13>
  VSS10  = GND
  DQ16_A  = M_D_CPU1_SA_DQ<16>
  VSS11  = GND
  DQ17_A  = M_D_CPU1_SA_DQ<17>
  VSS12  = GND
  DQS2_A_T  = M_D_CPU1_SA_DQS_DP<2>
  DQS2_A_C  = M_D_CPU1_SA_DQS_DN<2>
  VSS13  = GND
  DQ20_A  = M_D_CPU1_SA_DQ<20>
  VSS14  = GND
  DQ21_A  = M_D_CPU1_SA_DQ<21>
  VSS15  = GND
  DQ24_A  = M_D_CPU1_SA_DQ<24>
  VSS16  = GND
  DQ25_A  = M_D_CPU1_SA_DQ<25>
  VSS17  = GND
  DQS3_A_T  = M_D_CPU1_SA_DQS_DP<3>
  DQS3_A_C  = M_D_CPU1_SA_DQS_DN<3>
  VSS18  = GND
  DQ28_A  = M_D_CPU1_SA_DQ<28>
  VSS19  = GND
  DQ29_A  = M_D_CPU1_SA_DQ<29>
  VSS20  = GND
  CB0_A  = M_D_CPU1_SA_CB<0>
  VSS21  = GND
  CB1_A  = M_D_CPU1_SA_CB<1>
  VSS22  = GND
  DQS4_A_T  = M_D_CPU1_SA_DQS_DP<4>
  DQS4_A_C  = M_D_CPU1_SA_DQS_DN<4>
  VSS23  = GND
  CB4_A  = M_D_CPU1_SA_CB<4>
  VSS24  = GND
  CB5_A  = M_D_CPU1_SA_CB<5>
  VSS25  = GND
  ALERT_N  = M_D_CPU1_ALERT_N
  VSS26  = GND
  CS0_A_N  = M_D_CPU1_SA_CS_N<2>
  VSS27  = GND
  CA0_A  = M_D_CPU1_SA_CA<0>
  VSS28  = GND
  CA2_A  = M_D_CPU1_SA_CA<2>
  VSS29  = GND
  CA4_A  = M_D_CPU1_SA_CA<4>
  VSS30  = GND
  CA6_A  = M_D_CPU1_SA_CA<6>
  VSS31  = GND
  PAR_A  = M_D_CPU1_SA_PAR
  VSS32  = GND
  CA0_B  = M_D_CPU1_SB_CA<0>
  VSS33  = GND
  CA2_B  = M_D_CPU1_SB_CA<2>
  VSS34  = GND
  CA4_B  = M_D_CPU1_SB_CA<4>
  VSS35  = GND
  CA6_B  = M_D_CPU1_SB_CA<6>
  VSS36  = GND
  CS0_B_N  = M_D_CPU1_SB_CS_N<2>
  VSS37  = GND
  \lbd||rsp_a_n\  = M_D_CPU1_SA_RSP<1>
  \lbs||rsp_b_n\  = M_D_CPU1_SB_RSP<1>
  VSS38  = GND
  CB4_B  = M_D_CPU1_SB_CB<4>
  VSS39  = GND
  CB5_B  = M_D_CPU1_SB_CB<5>
  VSS40  = GND
  \dqs9_b_t||tdqs9_b_t||dbi4_b_n\  = M_D_CPU1_SB_DQS_DP<9>
  \dqs9_b_c||tdqs9_b_c\  = M_D_CPU1_SB_DQS_DN<9>
  VSS41  = GND
  CB0_B  = M_D_CPU1_SB_CB<0>
  VSS42  = GND
  CB1_B  = M_D_CPU1_SB_CB<1>
  VSS43  = GND
  DQ0_B  = M_D_CPU1_SB_DQ<0>
  VSS44  = GND
  DQ1_B  = M_D_CPU1_SB_DQ<1>
  VSS45  = GND
  DQS0_B_T  = M_D_CPU1_SB_DQS_DP<0>
  DQS0_B_C  = M_D_CPU1_SB_DQS_DN<0>
  VSS46  = GND
  DQ4_B  = M_D_CPU1_SB_DQ<4>
  VSS47  = GND
  DQ5_B  = M_D_CPU1_SB_DQ<5>
  VSS48  = GND
  DQ8_B  = M_D_CPU1_SB_DQ<8>
  VSS49  = GND
  DQ9_B  = M_D_CPU1_SB_DQ<9>
  VSS50  = GND
  DQS1_B_T  = M_D_CPU1_SB_DQS_DP<1>
  DQS1_B_C  = M_D_CPU1_SB_DQS_DN<1>
  VSS51  = GND
  DQ12_B  = M_D_CPU1_SB_DQ<12>
  VSS52  = GND
  DQ13_B  = M_D_CPU1_SB_DQ<13>
  VSS53  = GND
  DQ16_B  = M_D_CPU1_SB_DQ<16>
  VSS54  = GND
  DQ17_B  = M_D_CPU1_SB_DQ<17>
  VSS55  = GND
  DQS2_B_T  = M_D_CPU1_SB_DQS_DP<2>
  DQS2_B_C  = M_D_CPU1_SB_DQS_DN<2>
  VSS56  = GND
  DQ20_B  = M_D_CPU1_SB_DQ<20>
  VSS57  = GND
  DQ21_B  = M_D_CPU1_SB_DQ<21>
  VSS58  = GND
  DQ24_B  = M_D_CPU1_SB_DQ<24>
  VSS59  = GND
  DQ25_B  = M_D_CPU1_SB_DQ<25>
  VSS60  = GND
  DQS3_B_T  = M_D_CPU1_SB_DQS_DP<3>
  DQS3_B_C  = M_D_CPU1_SB_DQS_DN<3>
  VSS61  = GND
  DQ28_B  = M_D_CPU1_SB_DQ<28>
  VSS62  = GND
  DQ29_B  = M_D_CPU1_SB_DQ<29>
  VSS63  = GND
  RFU1  = TP_CHD_CPU1_DIMM2_FRU_1
  VIN_BULK1  = P12V_S3_AUX_CPU1_NVDIMM
  VIN_BULK2  = P12V_S3_AUX_CPU1_NVDIMM
  \pwr_good||fail_n\  = PWRGD_CHD_CPU1_DIMM2
  HSA  = PD_CHD_CPU1_DIMM2_SAA
  RFU2  = TP_CHD_CPU1_DIMM2_FRU_2
  RFU3  = TP_CHD_CPU1_DIMM2_FRU_3
  VSS64  = GND
  DQ2_A  = M_D_CPU1_SA_DQ<2>
  VSS65  = GND
  DQ3_A  = M_D_CPU1_SA_DQ<3>
  VSS66  = GND
  \dqs5_a_c||tdqs5_a_c||dqs5_a_t||tdqs5_a_t\  = M_D_CPU1_SA_DQS_DN<5>
  \dqs5_a_t||tdqs5_a_t\  = M_D_CPU1_SA_DQS_DP<5>
  VSS67  = GND
  DQ6_A  = M_D_CPU1_SA_DQ<6>
  VSS68  = GND
  DQ7_A  = M_D_CPU1_SA_DQ<7>
  VSS69  = GND
  DQ10_A  = M_D_CPU1_SA_DQ<10>
  VSS70  = GND
  DQ11_A  = M_D_CPU1_SA_DQ<11>
  VSS71  = GND
  \dqs6_a_c||tdqs6_a_c||dqs6_a_t||tdqs6_a_t\  = M_D_CPU1_SA_DQS_DN<6>
  \dqs6_a_t||tdqs6_a_t\  = M_D_CPU1_SA_DQS_DP<6>
  VSS72  = GND
  DQ14_A  = M_D_CPU1_SA_DQ<14>
  VSS73  = GND
  DQ15_A  = M_D_CPU1_SA_DQ<15>
  VSS74  = GND
  DQ18_A  = M_D_CPU1_SA_DQ<18>
  VSS75  = GND
  DQ19_A  = M_D_CPU1_SA_DQ<19>
  VSS76  = GND
  \dqs7_a_c||tdqs7_a_c\  = M_D_CPU1_SA_DQS_DN<7>
  \dqs7_a_t||tdqs7_a_t\  = M_D_CPU1_SA_DQS_DP<7>
  VSS77  = GND
  DQ22_A  = M_D_CPU1_SA_DQ<22>
  VSS78  = GND
  DQ23_A  = M_D_CPU1_SA_DQ<23>
  VSS79  = GND
  DQ26_A  = M_D_CPU1_SA_DQ<26>
  VSS80  = GND
  DQ27_A  = M_D_CPU1_SA_DQ<27>
  VSS81  = GND
  \dqs8_a_c||tdqs8_a_c\  = M_D_CPU1_SA_DQS_DN<8>
  \dqs8_a_t||tdqs8_a_t\  = M_D_CPU1_SA_DQS_DP<8>
  VSS82  = GND
  DQ30_A  = M_D_CPU1_SA_DQ<30>
  VSS83  = GND
  DQ31_A  = M_D_CPU1_SA_DQ<31>
  VSS84  = GND
  CB2_A  = M_D_CPU1_SA_CB<2>
  VSS85  = GND
  CB3_A  = M_D_CPU1_SA_CB<3>
  VSS86  = GND
  \dqs9_a_c||tdqs9_a_c\  = M_D_CPU1_SA_DQS_DN<9>
  \dqs9_a_t||tdqs9_a_t\  = M_D_CPU1_SA_DQS_DP<9>
  VSS87  = GND
  CB6_A  = M_D_CPU1_SA_CB<6>
  VSS88  = GND
  CB7_A  = M_D_CPU1_SA_CB<7>
  VSS89  = GND
  RESET_N  = RST_M_CD_CPU1_FPGA_N
  VSS90  = GND
  CS1_A_N  = M_D_CPU1_SA_CS_N<3>
  VSS91  = GND
  CA1_A  = M_D_CPU1_SA_CA<1>
  VSS92  = GND
  CA3_A  = M_D_CPU1_SA_CA<3>
  VSS93  = GND
  CA5_A  = M_D_CPU1_SA_CA<5>
  VSS94  = GND
  CK_T  = M_D_CPU1_CLK_DP<1>
  CK_C  = M_D_CPU1_CLK_DN<1>
  VSS95  = GND
  RFU4  = TP_CHD_CPU1_DIMM2_FRU_4
  CA1_B  = M_D_CPU1_SB_CA<1>
  VSS96  = GND
  CA3_B  = M_D_CPU1_SB_CA<3>
  VSS97  = GND
  CA5_B  = M_D_CPU1_SB_CA<5>
  VSS98  = GND
  PAR_B  = M_D_CPU1_SB_PAR
  VSS99  = GND
  CS1_B_N  = M_D_CPU1_SB_CS_N<3>
  VSS100  = GND
  RFU5  = TP_CHD_CPU1_DIMM2_FRU_5
  RFU6  = TP_CHD_CPU1_DIMM2_FRU_6
  VSS101  = GND
  CB6_B  = M_D_CPU1_SB_CB<6>
  VSS102  = GND
  CB7_B  = M_D_CPU1_SB_CB<7>
  VSS103  = GND
  DQS4_B_C  = M_D_CPU1_SB_DQS_DN<4>
  DQS4_B_T  = M_D_CPU1_SB_DQS_DP<4>
  VSS104  = GND
  CB2_B  = M_D_CPU1_SB_CB<2>
  VSS105  = GND
  CB3_B  = M_D_CPU1_SB_CB<3>
  VSS106  = GND
  DQ2_B  = M_D_CPU1_SB_DQ<2>
  VSS107  = GND
  DQ3_B  = M_D_CPU1_SB_DQ<3>
  VSS108  = GND
  \dqs5_b_c||tdqs5_b_c\  = M_D_CPU1_SB_DQS_DN<5>
  \dqs5_b_t||tdqs5_b_t\  = M_D_CPU1_SB_DQS_DP<5>
  VSS109  = GND
  DQ6_B  = M_D_CPU1_SB_DQ<6>
  VSS110  = GND
  DQ7_B  = M_D_CPU1_SB_DQ<7>
  VSS111  = GND
  DQ10_B  = M_D_CPU1_SB_DQ<10>
  VSS112  = GND
  DQ11_B  = M_D_CPU1_SB_DQ<11>
  VSS113  = GND
  \dqs6_b_c||tdqs6_b_c\  = M_D_CPU1_SB_DQS_DN<6>
  \dqs6_b_t||tdqs6_b_t\  = M_D_CPU1_SB_DQS_DP<6>
  VSS114  = GND
  DQ14_B  = M_D_CPU1_SB_DQ<14>
  VSS115  = GND
  DQ15_B  = M_D_CPU1_SB_DQ<15>
  VSS116  = GND
  DQ18_B  = M_D_CPU1_SB_DQ<18>
  VSS117  = GND
  DQ19_B  = M_D_CPU1_SB_DQ<19>
  VSS118  = GND
  \dqs7_b_c||tdqs7_b_c\  = M_D_CPU1_SB_DQS_DN<7>
  \dqs7_b_t||tdqs7_b_t\  = M_D_CPU1_SB_DQS_DP<7>
  VSS119  = GND
  DQ22_B  = M_D_CPU1_SB_DQ<22>
  VSS120  = GND
  DQ23_B  = M_D_CPU1_SB_DQ<23>
  VSS121  = GND
  DQ26_B  = M_D_CPU1_SB_DQ<26>
  VSS122  = GND
  DQ27_B  = M_D_CPU1_SB_DQ<27>
  VSS123  = GND
  \dqs8_b_c||tdqs8_b_c\  = M_D_CPU1_SB_DQS_DN<8>
  \dqs8_b_t||tdqs8_b_t\  = M_D_CPU1_SB_DQS_DP<8>
  VSS124  = GND
  DQ30_B  = M_D_CPU1_SB_DQ<30>
  VSS125  = GND
  DQ31_B  = M_D_CPU1_SB_DQ<31>
  VSS126  = GND
  G1  = GND
  G2  = GND
  G3  = GND

(kicad_pcb
	(version 20260206)
	(generator "pcbnew")
	(generator_version "10.0")
	(general
		(thickness 1.6)
		(legacy_teardrops no)
	)
	(paper "A4")
	(title_block
		(title "03242023_DA0F0TMBIJ0_F0T_Motherboard_J_brd_V01_OCP.brd")
		(comment 1 "Grand Teton / footprint 1660 of 6105 (J24), pads 229-274 of 291")
	)
	(layers
		(0 "F.Cu" signal "TOP")
		(4 "In1.Cu" signal "GND")
		(6 "In2.Cu" signal "IN1")
		(8 "In3.Cu" signal "GND1")
		(10 "In4.Cu" signal "IN2")
		(12 "In5.Cu" signal "GND2")
		(14 "In6.Cu" signal "IN3")
		(16 "In7.Cu" signal "GND3")
		(18 "In8.Cu" signal "VCC")
		(20 "In9.Cu" signal "VCC1")
		(22 "In10.Cu" signal "GND4")
		(24 "In11.Cu" signal "IN4")
		(26 "In12.Cu" signal "GND5")
		(28 "In13.Cu" signal "IN5")
		(30 "In14.Cu" signal "GND6")
		(32 "In15.Cu" signal "IN6")
		(34 "In16.Cu" signal "GND7")
		(2 "B.Cu" signal "BOTTOM")
		(9 "F.Adhes" user "F.Adhesive")
		(11 "B.Adhes" user "B.Adhesive")
		(13 "F.Paste" user "Package Geometry/Pastemask Top")
		(15 "B.Paste" user "Package Geometry/Pastemask Bottom")
		(5 "F.SilkS" user "Ref Des/Silkscreen Top")
		(7 "B.SilkS" user "Ref Des/Silkscreen Bottom")
		(1 "F.Mask" user "Board Geometry/Soldermask Top")
		(3 "B.Mask" user "Board Geometry/Soldermask Bottom")
		(17 "Dwgs.User" user "User.Drawings")
		(19 "Cmts.User" user "User.Comments")
		(21 "Eco1.User" user "User.Eco1")
		(23 "Eco2.User" user "User.Eco2")
		(25 "Edge.Cuts" user "Board Geometry/Outline")
		(27 "Margin" user)
		(31 "F.CrtYd" user "Package Geometry/Place Bound Top")
		(29 "B.CrtYd" user "Package Geometry/Place Bound Bottom")
		(35 "F.Fab" user "Ref Des/Assembly Top")
		(33 "B.Fab" user "Ref Des/Assembly Bottom")
	)
	(footprint ""
		(layer "F.Cu")
		(at 17.73428 -258.091686)
		(property "Reference" "J24"
			(at -3.0607 -81.901792 0)
			(unlocked yes)
			(layer "F.SilkS")
			(effects
				(font
					(size 0.7874 0.5842)
					(thickness 0.1524)
				)
				(justify left)
			)
		)
		(property "Value" ""
			(at 0 0 0)
			(layer "F.Fab")
			(effects
				(font
					(size 1.27 1.27)
				)
			)
		)
		(duplicate_pad_numbers_are_jumpers no)
		(pad "229" smd rect
			(at 2.050034 13.17498 270)
			(size 0.519938 1.4986)
			(layers "F.Cu" "F.Mask" "F.Paste")
			(net "M_D_CPU1_SB_CS_N<3>")
		)
		(pad "230" smd rect
			(at 2.050034 14.025118 270)
			(size 0.519938 1.4986)
			(layers "F.Cu" "F.Mask" "F.Paste")
			(net "GND")
		)
		(pad "231" smd rect
			(at 2.050034 14.875002 270)
			(size 0.519938 1.4986)
			(layers "F.Cu" "F.Mask" "F.Paste")
			(net "TP_CHD_CPU1_DIMM2_FRU_5")
		)
		(pad "232" smd rect
			(at 2.050034 15.724886 270)
			(size 0.519938 1.4986)
			(layers "F.Cu" "F.Mask" "F.Paste")
			(net "TP_CHD_CPU1_DIMM2_FRU_6")
		)
		(pad "233" smd rect
			(at 2.050034 16.575024 270)
			(size 0.519938 1.4986)
			(layers "F.Cu" "F.Mask" "F.Paste")
			(net "GND")
		)
		(pad "234" smd rect
			(at 2.050034 17.424908 270)
			(size 0.519938 1.4986)
			(layers "F.Cu" "F.Mask" "F.Paste")
			(net "M_D_CPU1_SB_CB<6>")
		)
		(pad "235" smd rect
			(at 2.050034 18.275046 270)
			(size 0.519938 1.4986)
			(layers "F.Cu" "F.Mask" "F.Paste")
			(net "GND")
		)
		(pad "236" smd rect
			(at 2.050034 19.12493 270)
			(size 0.519938 1.4986)
			(layers "F.Cu" "F.Mask" "F.Paste")
			(net "M_D_CPU1_SB_CB<7>")
		)
		(pad "237" smd rect
			(at 2.050034 19.975068 270)
			(size 0.519938 1.4986)
			(layers "F.Cu" "F.Mask" "F.Paste")
			(net "GND")
		)
		(pad "238" smd rect
			(at 2.050034 20.824952 270)
			(size 0.519938 1.4986)
			(layers "F.Cu" "F.Mask" "F.Paste")
			(net "M_D_CPU1_SB_DQS_DN<4>")
		)
		(pad "239" smd rect
			(at 2.050034 21.67509 270)
			(size 0.519938 1.4986)
			(layers "F.Cu" "F.Mask" "F.Paste")
			(net "M_D_CPU1_SB_DQS_DP<4>")
		)
		(pad "240" smd rect
			(at 2.050034 22.524974 270)
			(size 0.519938 1.4986)
			(layers "F.Cu" "F.Mask" "F.Paste")
			(net "GND")
		)
		(pad "241" smd rect
			(at 2.050034 23.375112 270)
			(size 0.519938 1.4986)
			(layers "F.Cu" "F.Mask" "F.Paste")
			(net "M_D_CPU1_SB_CB<2>")
		)
		(pad "242" smd rect
			(at 2.050034 24.224996 270)
			(size 0.519938 1.4986)
			(layers "F.Cu" "F.Mask" "F.Paste")
			(net "GND")
		)
		(pad "243" smd rect
			(at 2.050034 25.07488 270)
			(size 0.519938 1.4986)
			(layers "F.Cu" "F.Mask" "F.Paste")
			(net "M_D_CPU1_SB_CB<3>")
		)
		(pad "244" smd rect
			(at 2.050034 25.925018 270)
			(size 0.519938 1.4986)
			(layers "F.Cu" "F.Mask" "F.Paste")
			(net "GND")
		)
		(pad "245" smd rect
			(at 2.050034 26.774902 270)
			(size 0.519938 1.4986)
			(layers "F.Cu" "F.Mask" "F.Paste")
			(net "M_D_CPU1_SB_DQ<2>")
		)
		(pad "246" smd rect
			(at 2.050034 27.62504 270)
			(size 0.519938 1.4986)
			(layers "F.Cu" "F.Mask" "F.Paste")
			(net "GND")
		)
		(pad "247" smd rect
			(at 2.050034 28.474924 270)
			(size 0.519938 1.4986)
			(layers "F.Cu" "F.Mask" "F.Paste")
			(net "M_D_CPU1_SB_DQ<3>")
		)
		(pad "248" smd rect
			(at 2.050034 29.325062 270)
			(size 0.519938 1.4986)
			(layers "F.Cu" "F.Mask" "F.Paste")
			(net "GND")
		)
		(pad "249" smd rect
			(at 2.050034 30.174946 270)
			(size 0.519938 1.4986)
			(layers "F.Cu" "F.Mask" "F.Paste")
			(net "M_D_CPU1_SB_DQS_DN<5>")
		)
		(pad "250" smd rect
			(at 2.050034 31.025084 270)
			(size 0.519938 1.4986)
			(layers "F.Cu" "F.Mask" "F.Paste")
			(net "M_D_CPU1_SB_DQS_DP<5>")
		)
		(pad "251" smd rect
			(at 2.050034 31.874968 270)
			(size 0.519938 1.4986)
			(layers "F.Cu" "F.Mask" "F.Paste")
			(net "GND")
		)
		(pad "252" smd rect
			(at 2.050034 32.725106 270)
			(size 0.519938 1.4986)
			(layers "F.Cu" "F.Mask" "F.Paste")
			(net "M_D_CPU1_SB_DQ<6>")
		)
		(pad "253" smd rect
			(at 2.050034 33.57499 270)
			(size 0.519938 1.4986)
			(layers "F.Cu" "F.Mask" "F.Paste")
			(net "GND")
		)
		(pad "254" smd rect
			(at 2.050034 34.425128 270)
			(size 0.519938 1.4986)
			(layers "F.Cu" "F.Mask" "F.Paste")
			(net "M_D_CPU1_SB_DQ<7>")
		)
		(pad "255" smd rect
			(at 2.050034 35.275012 270)
			(size 0.519938 1.4986)
			(layers "F.Cu" "F.Mask" "F.Paste")
			(net "GND")
		)
		(pad "256" smd rect
			(at 2.050034 36.124896 270)
			(size 0.519938 1.4986)
			(layers "F.Cu" "F.Mask" "F.Paste")
			(net "M_D_CPU1_SB_DQ<10>")
		)
		(pad "257" smd rect
			(at 2.050034 36.975034 270)
			(size 0.519938 1.4986)
			(layers "F.Cu" "F.Mask" "F.Paste")
			(net "GND")
		)
		(pad "258" smd rect
			(at 2.050034 37.824918 270)
			(size 0.519938 1.4986)
			(layers "F.Cu" "F.Mask" "F.Paste")
			(net "M_D_CPU1_SB_DQ<11>")
		)
		(pad "259" smd rect
			(at 2.050034 38.675056 270)
			(size 0.519938 1.4986)
			(layers "F.Cu" "F.Mask" "F.Paste")
			(net "GND")
		)
		(pad "260" smd rect
			(at 2.050034 39.52494 270)
			(size 0.519938 1.4986)
			(layers "F.Cu" "F.Mask" "F.Paste")
			(net "M_D_CPU1_SB_DQS_DN<6>")
		)
		(pad "261" smd rect
			(at 2.050034 40.375078 270)
			(size 0.519938 1.4986)
			(layers "F.Cu" "F.Mask" "F.Paste")
			(net "M_D_CPU1_SB_DQS_DP<6>")
		)
		(pad "262" smd rect
			(at 2.050034 41.224962 270)
			(size 0.519938 1.4986)
			(layers "F.Cu" "F.Mask" "F.Paste")
			(net "GND")
		)
		(pad "263" smd rect
			(at 2.050034 42.0751 270)
			(size 0.519938 1.4986)
			(layers "F.Cu" "F.Mask" "F.Paste")
			(net "M_D_CPU1_SB_DQ<14>")
		)
		(pad "264" smd rect
			(at 2.050034 42.924984 270)
			(size 0.519938 1.4986)
			(layers "F.Cu" "F.Mask" "F.Paste")
			(net "GND")
		)
		(pad "265" smd rect
			(at 2.050034 43.775122 270)
			(size 0.519938 1.4986)
			(layers "F.Cu" "F.Mask" "F.Paste")
			(net "M_D_CPU1_SB_DQ<15>")
		)
		(pad "266" smd rect
			(at 2.050034 44.625006 270)
			(size 0.519938 1.4986)
			(layers "F.Cu" "F.Mask" "F.Paste")
			(net "GND")
		)
		(pad "267" smd rect
			(at 2.050034 45.47489 270)
			(size 0.519938 1.4986)
			(layers "F.Cu" "F.Mask" "F.Paste")
			(net "M_D_CPU1_SB_DQ<18>")
		)
		(pad "268" smd rect
			(at 2.050034 46.325028 270)
			(size 0.519938 1.4986)
			(layers "F.Cu" "F.Mask" "F.Paste")
			(net "GND")
		)
		(pad "269" smd rect
			(at 2.050034 47.174912 270)
			(size 0.519938 1.4986)
			(layers "F.Cu" "F.Mask" "F.Paste")
			(net "M_D_CPU1_SB_DQ<19>")
		)
		(pad "270" smd rect
			(at 2.050034 48.02505 270)
			(size 0.519938 1.4986)
			(layers "F.Cu" "F.Mask" "F.Paste")
			(net "GND")
		)
		(pad "271" smd rect
			(at 2.050034 48.874934 270)
			(size 0.519938 1.4986)
			(layers "F.Cu" "F.Mask" "F.Paste")
			(net "M_D_CPU1_SB_DQS_DN<7>")
		)
		(pad "272" smd rect
			(at 2.050034 49.725072 270)
			(size 0.519938 1.4986)
			(layers "F.Cu" "F.Mask" "F.Paste")
			(net "M_D_CPU1_SB_DQS_DP<7>")
		)
		(pad "273" smd rect
			(at 2.050034 50.574956 270)
			(size 0.519938 1.4986)
			(layers "F.Cu" "F.Mask" "F.Paste")
			(net "GND")
		)
		(pad "274" smd rect
			(at 2.050034 51.425094 270)
			(size 0.519938 1.4986)
			(layers "F.Cu" "F.Mask" "F.Paste")
			(net "M_D_CPU1_SB_DQ<22>")
		)
	)
)
